(kicad_pcb
	(version 20260206)
	(generator "pcbnew")
	(generator_version "10.0")
	(general
		(thickness 1.6)
		(legacy_teardrops no)
	)
	(paper "A4")
	(title_block
		(title "baseboard — 13948-1b.1110WZS1818.brd")
		(comment 1 "Honey Badger (Wiwynn) / footprints 1000-1007 of 2523")
	)
	(layers
		(0 "F.Cu" signal "TOP")
		(4 "In1.Cu" signal "L2GND")
		(6 "In2.Cu" signal "L3")
		(8 "In3.Cu" signal "L4VCC")
		(10 "In4.Cu" signal "L5VCC")
		(12 "In5.Cu" signal "L6")
		(14 "In6.Cu" signal "L7GND")
		(2 "B.Cu" signal "BOTTOM")
		(9 "F.Adhes" user "F.Adhesive")
		(11 "B.Adhes" user "B.Adhesive")
		(13 "F.Paste" user "Package Geometry/Pastemask Top")
		(15 "B.Paste" user "Package Geometry/Pastemask Bottom")
		(5 "F.SilkS" user "Ref Des/Silkscreen Top")
		(7 "B.SilkS" user "Ref Des/Silkscreen Bottom")
		(1 "F.Mask" user "Board Geometry/Soldermask Top")
		(3 "B.Mask" user "Board Geometry/Soldermask Bottom")
		(17 "Dwgs.User" user "User.Drawings")
		(19 "Cmts.User" user "User.Comments")
		(21 "Eco1.User" user "User.Eco1")
		(23 "Eco2.User" user "User.Eco2")
		(25 "Edge.Cuts" user "Board Geometry/Outline")
		(27 "Margin" user)
		(31 "F.CrtYd" user "Package Geometry/Place Bound Top")
		(29 "B.CrtYd" user "Package Geometry/Place Bound Bottom")
		(35 "F.Fab" user "Ref Des/Assembly Top")
		(33 "B.Fab" user "Ref Des/Assembly Bottom")
	)
	(footprint ""
		(layer "F.Cu")
		(at 20.016216 -213.79688 180)
		(property "Reference" "SR263"
			(at 0 0 180)
			(layer "F.SilkS")
			(hide yes)
			(effects
				(font
					(size 1.27 1.27)
				)
			)
		)
		(property "Value" "4K7R2F-GP"
			(at 0.064008 -3.993896 180)
			(unlocked yes)
			(layer "F.Fab")
			(hide yes)
			(effects
				(font
					(size 1.016 1.016)
					(thickness 0.1524)
				)
			)
		)
		(property "Device Type" "R402H16"
			(at 0.064008 -5.517896 180)
			(unlocked yes)
			(layer "F.Fab")
			(hide yes)
			(effects
				(font
					(size 1.016 1.016)
					(thickness 0.1524)
				)
			)
		)
		(duplicate_pad_numbers_are_jumpers no)
		(fp_line
			(start 0.508 -0.9398)
			(end -0.508 -0.9398)
			(stroke
				(width 0.1524)
				(type default)
			)
			(layer "F.SilkS")
		)
		(fp_line
			(start -0.508 -0.9398)
			(end -0.508 0.9398)
			(stroke
				(width 0.1524)
				(type default)
			)
			(layer "F.SilkS")
		)
		(fp_rect
			(start -0.508 0.9398)
			(end 0.508 -0.9398)
			(stroke
				(width 0)
				(type default)
			)
			(fill no)
			(layer "F.CrtYd")
		)
		(fp_rect
			(start -0.508 0.9398)
			(end 0.508 -0.9398)
			(stroke
				(width 0)
				(type default)
			)
			(fill no)
			(layer "F.Fab")
		)
		(pad "1" smd custom
			(at 0 -0.4445 180)
			(size 0.1397 0.1397)
			(layers "F.Cu" "F.Mask" "F.Paste")
			(net "P3V3_STBY")
			(options
				(clearance outline)
				(anchor circle)
			)
			(primitives
				(gr_poly
					(pts
						(arc
							(start -0.1778 -0.2794)
							(mid -0.249642 -0.249642)
							(end -0.2794 -0.1778)
						)
						(arc
							(start -0.2794 0.1778)
							(mid -0.249642 0.249642)
							(end -0.1778 0.2794)
						)
						(arc
							(start 0.1778 0.2794)
							(mid 0.249642 0.249642)
							(end 0.2794 0.1778)
						)
						(arc
							(start 0.2794 -0.1778)
							(mid 0.249642 -0.249642)
							(end 0.1778 -0.2794)
						)
					)
					(width 0)
					(fill yes)
				)
			)
		)
		(pad "2" smd custom
			(at 0 0.4445 180)
			(size 0.1397 0.1397)
			(layers "F.Cu" "F.Mask" "F.Paste")
			(net "I2C_IO_EXP_RESET#_PWR")
			(options
				(clearance outline)
				(anchor circle)
			)
			(primitives
				(gr_poly
					(pts
						(arc
							(start -0.1778 -0.2794)
							(mid -0.249642 -0.249642)
							(end -0.2794 -0.1778)
						)
						(arc
							(start -0.2794 0.1778)
							(mid -0.249642 0.249642)
							(end -0.1778 0.2794)
						)
						(arc
							(start 0.1778 0.2794)
							(mid 0.249642 0.249642)
							(end 0.2794 0.1778)
						)
						(arc
							(start 0.2794 -0.1778)
							(mid 0.249642 -0.249642)
							(end 0.1778 -0.2794)
						)
					)
					(width 0)
					(fill yes)
				)
			)
		)
	)
	(footprint ""
		(layer "F.Cu")
		(at 92.21597 -97.79 -90)
		(property "Reference" "SR777"
			(at 0 0 270)
			(layer "F.SilkS")
			(hide yes)
			(effects
				(font
					(size 1.27 1.27)
				)
			)
		)
		(property "Value" "4K7R2F-GP"
			(at 0.064008 -3.993896 270)
			(unlocked yes)
			(layer "F.Fab")
			(hide yes)
			(effects
				(font
					(size 1.016 1.016)
					(thickness 0.1524)
				)
			)
		)
		(property "Device Type" "R402H16"
			(at 0.064008 -5.517896 270)
			(unlocked yes)
			(layer "F.Fab")
			(hide yes)
			(effects
				(font
					(size 1.016 1.016)
					(thickness 0.1524)
				)
			)
		)
		(duplicate_pad_numbers_are_jumpers no)
		(fp_line
			(start -0.508 -0.9398)
			(end -0.508 0.9398)
			(stroke
				(width 0.1524)
				(type default)
			)
			(layer "F.SilkS")
		)
		(fp_line
			(start 0.508 -0.9398)
			(end -0.508 -0.9398)
			(stroke
				(width 0.1524)
				(type default)
			)
			(layer "F.SilkS")
		)
		(fp_rect
			(start -0.508 0.9398)
			(end 0.508 -0.9398)
			(stroke
				(width 0)
				(type default)
			)
			(fill no)
			(layer "F.CrtYd")
		)
		(fp_rect
			(start -0.508 0.9398)
			(end 0.508 -0.9398)
			(stroke
				(width 0)
				(type default)
			)
			(fill no)
			(layer "F.Fab")
		)
		(pad "1" smd custom
			(at 0 -0.4445 270)
			(size 0.1397 0.1397)
			(layers "F.Cu" "F.Mask" "F.Paste")
			(net "EXP_XM_ADDR_16")
			(options
				(clearance outline)
				(anchor circle)
			)
			(primitives
				(gr_poly
					(pts
						(arc
							(start -0.1778 -0.2794)
							(mid -0.249642 -0.249642)
							(end -0.2794 -0.1778)
						)
						(arc
							(start -0.2794 0.1778)
							(mid -0.249642 0.249642)
							(end -0.1778 0.2794)
						)
						(arc
							(start 0.1778 0.2794)
							(mid 0.249642 0.249642)
							(end 0.2794 0.1778)
						)
						(arc
							(start 0.2794 -0.1778)
							(mid 0.249642 -0.249642)
							(end 0.1778 -0.2794)
						)
					)
					(width 0)
					(fill yes)
				)
			)
		)
		(pad "2" smd custom
			(at 0 0.4445 270)
			(size 0.1397 0.1397)
			(layers "F.Cu" "F.Mask" "F.Paste")
			(net "GND")
			(options
				(clearance outline)
				(anchor circle)
			)
			(primitives
				(gr_poly
					(pts
						(arc
							(start -0.1778 -0.2794)
							(mid -0.249642 -0.249642)
							(end -0.2794 -0.1778)
						)
						(arc
							(start -0.2794 0.1778)
							(mid -0.249642 0.249642)
							(end -0.1778 0.2794)
						)
						(arc
							(start 0.1778 0.2794)
							(mid 0.249642 0.249642)
							(end 0.2794 0.1778)
						)
						(arc
							(start 0.2794 -0.1778)
							(mid 0.249642 -0.249642)
							(end 0.1778 -0.2794)
						)
					)
					(width 0)
					(fill yes)
				)
			)
		)
	)
	(footprint ""
		(layer "F.Cu")
		(at 278.3586 -183.388)
		(property "Reference" "TP146"
			(at 0 0 0)
			(layer "F.SilkS")
			(hide yes)
			(effects
				(font
					(size 1.27 1.27)
				)
			)
		)
		(property "Value" "TPAD28"
			(at 0.0127 -1.8034 0)
			(unlocked yes)
			(layer "F.Fab")
			(hide yes)
			(effects
				(font
					(size 1.016 1.016)
					(thickness 0.1524)
				)
			)
		)
		(property "Device Type" "TPAD28"
			(at 0.0127 -3.3274 0)
			(unlocked yes)
			(layer "F.Fab")
			(hide yes)
			(effects
				(font
					(size 1.016 1.016)
					(thickness 0.1524)
				)
			)
		)
		(duplicate_pad_numbers_are_jumpers no)
		(fp_poly
			(pts
				(arc
					(start 0.3556 0)
					(mid -0.3556 0)
					(end 0.3556 0)
				)
			)
			(stroke
				(width 0)
				(type default)
			)
			(fill no)
			(layer "F.CrtYd")
		)
		(fp_poly
			(pts
				(arc
					(start 0.6096 0)
					(mid -0.6096 0)
					(end 0.6096 0)
				)
			)
			(stroke
				(width 0)
				(type default)
			)
			(fill no)
			(layer "F.Fab")
		)
		(pad "1" smd circle
			(at 0 0)
			(size 0.7112 0.7112)
			(layers "F.Cu" "F.Mask" "F.Paste")
			(net "TP_BMC_GPIOR4")
		)
	)
	(footprint ""
		(layer "F.Cu")
		(at 344.424 -114.808 -90)
		(property "Reference" "PC9"
			(at 0 0 270)
			(layer "F.SilkS")
			(hide yes)
			(effects
				(font
					(size 1.27 1.27)
				)
			)
		)
		(property "Value" "SC1U10V2KX-1GP"
			(at 1.1811 -2.7051 270)
			(unlocked yes)
			(layer "F.Fab")
			(hide yes)
			(effects
				(font
					(size 1.016 1.016)
					(thickness 0.1524)
				)
			)
		)
		(property "Device Type" "C402H22"
			(at 1.1811 -4.2291 270)
			(unlocked yes)
			(layer "F.Fab")
			(hide yes)
			(effects
				(font
					(size 1.016 1.016)
					(thickness 0.1524)
				)
			)
		)
		(duplicate_pad_numbers_are_jumpers no)
		(fp_rect
			(start -0.4318 0.9525)
			(end 0.4318 -0.9525)
			(stroke
				(width 0)
				(type default)
			)
			(fill no)
			(layer "F.CrtYd")
		)
		(fp_rect
			(start -0.4318 0.9525)
			(end 0.4318 -0.9525)
			(stroke
				(width 0)
				(type default)
			)
			(fill no)
			(layer "F.Fab")
		)
		(pad "1" smd custom
			(at 0 -0.4445 270)
			(size 0.1524 0.1524)
			(layers "F.Cu" "F.Mask" "F.Paste")
			(net "P5V_STBY_CC_R")
			(options
				(clearance outline)
				(anchor circle)
			)
			(primitives
				(gr_poly
					(pts
						(arc
							(start 0.3048 -0.2032)
							(mid 0.275042 -0.275042)
							(end 0.2032 -0.3048)
						)
						(arc
							(start -0.2032 -0.3048)
							(mid -0.275042 -0.275042)
							(end -0.3048 -0.2032)
						)
						(arc
							(start -0.3048 0.2032)
							(mid -0.275042 0.275042)
							(end -0.2032 0.3048)
						)
						(arc
							(start 0.2032 0.3048)
							(mid 0.275042 0.275042)
							(end 0.3048 0.2032)
						)
					)
					(width 0)
					(fill yes)
				)
			)
		)
		(pad "2" smd custom
			(at 0 0.4445 270)
			(size 0.1524 0.1524)
			(layers "F.Cu" "F.Mask" "F.Paste")
			(net "P5V_STBY_VFB")
			(options
				(clearance outline)
				(anchor circle)
			)
			(primitives
				(gr_poly
					(pts
						(arc
							(start 0.3048 -0.2032)
							(mid 0.275042 -0.275042)
							(end 0.2032 -0.3048)
						)
						(arc
							(start -0.2032 -0.3048)
							(mid -0.275042 -0.275042)
							(end -0.3048 -0.2032)
						)
						(arc
							(start -0.3048 0.2032)
							(mid -0.275042 0.275042)
							(end -0.2032 0.3048)
						)
						(arc
							(start 0.2032 0.3048)
							(mid 0.275042 0.275042)
							(end 0.3048 0.2032)
						)
					)
					(width 0)
					(fill yes)
				)
			)
		)
	)
	(footprint ""
		(layer "F.Cu")
		(at 48.768 -215.392 -90)
		(property "Reference" "C7273"
			(at 0 0 270)
			(layer "F.SilkS")
			(hide yes)
			(effects
				(font
					(size 1.27 1.27)
				)
			)
		)
		(property "Value" "SCD01U16V2KX-3GP"
			(at 1.1811 -2.7051 270)
			(unlocked yes)
			(layer "F.Fab")
			(hide yes)
			(effects
				(font
					(size 1.016 1.016)
					(thickness 0.1524)
				)
			)
		)
		(property "Device Type" "C402H22"
			(at 1.1811 -4.2291 270)
			(unlocked yes)
			(layer "F.Fab")
			(hide yes)
			(effects
				(font
					(size 1.016 1.016)
					(thickness 0.1524)
				)
			)
		)
		(duplicate_pad_numbers_are_jumpers no)
		(fp_rect
			(start -0.4318 0.9525)
			(end 0.4318 -0.9525)
			(stroke
				(width 0)
				(type default)
			)
			(fill no)
			(layer "F.CrtYd")
		)
		(fp_rect
			(start -0.4318 0.9525)
			(end 0.4318 -0.9525)
			(stroke
				(width 0)
				(type default)
			)
			(fill no)
			(layer "F.Fab")
		)
		(pad "1" smd custom
			(at 0 -0.4445 270)
			(size 0.1524 0.1524)
			(layers "F.Cu" "F.Mask" "F.Paste")
			(net "MB0_TIME_R")
			(options
				(clearance outline)
				(anchor circle)
			)
			(primitives
				(gr_poly
					(pts
						(arc
							(start 0.3048 -0.2032)
							(mid 0.275042 -0.275042)
							(end 0.2032 -0.3048)
						)
						(arc
							(start -0.2032 -0.3048)
							(mid -0.275042 -0.275042)
							(end -0.3048 -0.2032)
						)
						(arc
							(start -0.3048 0.2032)
							(mid -0.275042 0.275042)
							(end -0.2032 0.3048)
						)
						(arc
							(start 0.2032 0.3048)
							(mid 0.275042 0.275042)
							(end 0.3048 0.2032)
						)
					)
					(width 0)
					(fill yes)
				)
			)
		)
		(pad "2" smd custom
			(at 0 0.4445 270)
			(size 0.1524 0.1524)
			(layers "F.Cu" "F.Mask" "F.Paste")
			(net "AGND_CURRENT_MON")
			(options
				(clearance outline)
				(anchor circle)
			)
			(primitives
				(gr_poly
					(pts
						(arc
							(start 0.3048 -0.2032)
							(mid 0.275042 -0.275042)
							(end 0.2032 -0.3048)
						)
						(arc
							(start -0.2032 -0.3048)
							(mid -0.275042 -0.275042)
							(end -0.3048 -0.2032)
						)
						(arc
							(start -0.3048 0.2032)
							(mid -0.275042 0.275042)
							(end -0.2032 0.3048)
						)
						(arc
							(start 0.2032 0.3048)
							(mid 0.275042 0.275042)
							(end 0.3048 0.2032)
						)
					)
					(width 0)
					(fill yes)
				)
			)
		)
	)
	(footprint ""
		(layer "F.Cu")
		(at 275.336 -36.83 180)
		(property "Reference" "PR49"
			(at 0 0 180)
			(layer "F.SilkS")
			(hide yes)
			(effects
				(font
					(size 1.27 1.27)
				)
			)
		)
		(property "Value" "3D01R5F-GP"
			(at 0 -8.9535 180)
			(unlocked yes)
			(layer "F.Fab")
			(hide yes)
			(effects
				(font
					(size 1.27 1.016)
					(thickness 0.1524)
				)
			)
		)
		(property "Device Type" "R805H24"
			(at 0 -10.6299 180)
			(unlocked yes)
			(layer "F.Fab")
			(hide yes)
			(effects
				(font
					(size 1.27 1.016)
					(thickness 0.1524)
				)
			)
		)
		(duplicate_pad_numbers_are_jumpers no)
		(fp_line
			(start 0.889 1.7018)
			(end 0.889 -0.508)
			(stroke
				(width 0.1524)
				(type default)
			)
			(layer "F.SilkS")
		)
		(fp_line
			(start 0.889 -1.7018)
			(end 0.889 -0.381)
			(stroke
				(width 0.1524)
				(type default)
			)
			(layer "F.SilkS")
		)
		(fp_line
			(start 0.889 -1.7018)
			(end -0.889 -1.7018)
			(stroke
				(width 0.1524)
				(type default)
			)
			(layer "F.SilkS")
		)
		(fp_line
			(start -0.889 1.7018)
			(end 0.889 1.7018)
			(stroke
				(width 0.1524)
				(type default)
			)
			(layer "F.SilkS")
		)
		(fp_line
			(start -0.889 0.0762)
			(end -0.889 1.7018)
			(stroke
				(width 0.1524)
				(type default)
			)
			(layer "F.SilkS")
		)
		(fp_line
			(start -0.889 -1.7018)
			(end -0.889 0.2794)
			(stroke
				(width 0.1524)
				(type default)
			)
			(layer "F.SilkS")
		)
		(fp_poly
			(pts
				(xy 0.9652 -1.778) (xy 0.9652 1.778) (xy -0.9652 1.778) (xy -0.9652 -1.778)
			)
			(stroke
				(width 0)
				(type default)
			)
			(fill no)
			(layer "F.CrtYd")
		)
		(fp_rect
			(start -0.9652 1.778)
			(end 0.9652 -1.778)
			(stroke
				(width 0)
				(type default)
			)
			(fill no)
			(layer "F.Fab")
		)
		(pad "1" smd rect
			(at 0 -0.9652 180)
			(size 1.397 1.143)
			(layers "F.Cu" "F.Mask" "F.Paste")
			(net "P1V8_STBY_SNB")
		)
		(pad "2" smd rect
			(at 0 0.9652 180)
			(size 1.397 1.143)
			(layers "F.Cu" "F.Mask" "F.Paste")
			(net "GND")
		)
	)
	(footprint ""
		(layer "F.Cu")
		(at 108.14177 -78.6892)
		(property "Reference" "STP156"
			(at 0 0 0)
			(layer "F.SilkS")
			(hide yes)
			(effects
				(font
					(size 1.27 1.27)
				)
			)
		)
		(property "Value" "TPAD28"
			(at 0.0127 -1.8034 0)
			(unlocked yes)
			(layer "F.Fab")
			(hide yes)
			(effects
				(font
					(size 1.016 1.016)
					(thickness 0.1524)
				)
			)
		)
		(property "Device Type" "TPAD28"
			(at 0.0127 -3.3274 0)
			(unlocked yes)
			(layer "F.Fab")
			(hide yes)
			(effects
				(font
					(size 1.016 1.016)
					(thickness 0.1524)
				)
			)
		)
		(duplicate_pad_numbers_are_jumpers no)
		(fp_poly
			(pts
				(arc
					(start 0.3556 0)
					(mid -0.3556 0)
					(end 0.3556 0)
				)
			)
			(stroke
				(width 0)
				(type default)
			)
			(fill no)
			(layer "F.CrtYd")
		)
		(fp_poly
			(pts
				(arc
					(start 0.6096 0)
					(mid -0.6096 0)
					(end 0.6096 0)
				)
			)
			(stroke
				(width 0)
				(type default)
			)
			(fill no)
			(layer "F.Fab")
		)
		(pad "1" smd circle
			(at 0 0)
			(size 0.7112 0.7112)
			(layers "F.Cu" "F.Mask" "F.Paste")
			(net "EXP_LED_15")
		)
	)
	(footprint ""
		(layer "F.Cu")
		(at 188.087 -20.574 180)
		(property "Reference" "R459"
			(at 0 0 180)
			(layer "F.SilkS")
			(hide yes)
			(effects
				(font
					(size 1.27 1.27)
				)
			)
		)
		(property "Value" "4K75R2F-1-GP"
			(at 0.064008 -3.993896 180)
			(unlocked yes)
			(layer "F.Fab")
			(hide yes)
			(effects
				(font
					(size 1.016 1.016)
					(thickness 0.1524)
				)
			)
		)
		(property "Device Type" "R402H16"
			(at 0.064008 -5.517896 180)
			(unlocked yes)
			(layer "F.Fab")
			(hide yes)
			(effects
				(font
					(size 1.016 1.016)
					(thickness 0.1524)
				)
			)
		)
		(duplicate_pad_numbers_are_jumpers no)
		(fp_line
			(start 0.508 -0.9398)
			(end -0.508 -0.9398)
			(stroke
				(width 0.1524)
				(type default)
			)
			(layer "F.SilkS")
		)
		(fp_line
			(start -0.508 -0.9398)
			(end -0.508 0.9398)
			(stroke
				(width 0.1524)
				(type default)
			)
			(layer "F.SilkS")
		)
		(fp_rect
			(start -0.508 0.9398)
			(end 0.508 -0.9398)
			(stroke
				(width 0)
				(type default)
			)
			(fill no)
			(layer "F.CrtYd")
		)
		(fp_rect
			(start -0.508 0.9398)
			(end 0.508 -0.9398)
			(stroke
				(width 0)
				(type default)
			)
			(fill no)
			(layer "F.Fab")
		)
		(pad "1" smd custom
			(at 0 -0.4445 180)
			(size 0.1397 0.1397)
			(layers "F.Cu" "F.Mask" "F.Paste")
			(net "P3V3_STBY")
			(options
				(clearance outline)
				(anchor circle)
			)
			(primitives
				(gr_poly
					(pts
						(arc
							(start -0.1778 -0.2794)
							(mid -0.249642 -0.249642)
							(end -0.2794 -0.1778)
						)
						(arc
							(start -0.2794 0.1778)
							(mid -0.249642 0.249642)
							(end -0.1778 0.2794)
						)
						(arc
							(start 0.1778 0.2794)
							(mid 0.249642 0.249642)
							(end 0.2794 0.1778)
						)
						(arc
							(start 0.2794 -0.1778)
							(mid 0.249642 -0.249642)
							(end 0.1778 -0.2794)
						)
					)
					(width 0)
					(fill yes)
				)
			)
		)
		(pad "2" smd custom
			(at 0 0.4445 180)
			(size 0.1397 0.1397)
			(layers "F.Cu" "F.Mask" "F.Paste")
			(net "RMII_BMC_MDIO_R")
			(options
				(clearance outline)
				(anchor circle)
			)
			(primitives
				(gr_poly
					(pts
						(arc
							(start -0.1778 -0.2794)
							(mid -0.249642 -0.249642)
							(end -0.2794 -0.1778)
						)
						(arc
							(start -0.2794 0.1778)
							(mid -0.249642 0.249642)
							(end -0.1778 0.2794)
						)
						(arc
							(start 0.1778 0.2794)
							(mid 0.249642 0.249642)
							(end 0.2794 0.1778)
						)
						(arc
							(start 0.2794 -0.1778)
							(mid 0.249642 -0.249642)
							(end 0.1778 -0.2794)
						)
					)
					(width 0)
					(fill yes)
				)
			)
		)
	)
)
